FILE_TYPE = MACRO_DRAWING;
SET COLOR_WIRE YELLOW;
SET COLOR_PROP ORANGE;
SET COLOR_DOT WHITE;
SET COLOR_ARC YELLOW;
SET COLOR_BODY GREEN;
SET COLOR_NOTE PURPLE;
SET PROP_DISPLAY VALUE;
SET PAGE_NUMBER P10;
FORCEADD QUANTA_TITLE_BLOCK_C..1
(5975 -1500);
FORCEPROP 1 LAST CUSTOM_TXT_CDS <NAME_2>
J 0
(2800 -1450);
FORCEPROP 1 LAST CUSTOM_TXT_CDS <NAME_1>
J 0
(2800 -1325);
FORCEPROP 1 LAST CUSTOM_TXT_CDS <Q_NUMBER>
J 0
(4572 -1397);
DISPLAY 1.212766 (4572 -1397);
FORCEPROP 1 LAST CUSTOM_TXT_CDS <Q_PROJ>
J 0
(3593 -1398);
DISPLAY 1.212766 (3593 -1398);
FORCEPROP 1 LAST CUSTOM_TXT_CDS <Q_REV>
J 0
(5791 -1397);
DISPLAY 1.212766 (5791 -1397);
FORCEPROP 1 LAST CUSTOM_TXT_CDS <CON_LAST_MODIFIED>
J 0
(4090 -1485);
DISPLAY 0.978723 (4090 -1485);
FORCEPROP 1 LAST CUSTOM_TXT_CDS <CON_PAGE_NUM> OF <CON_TOTAL_PAGES>
J 0
(5529 -1482);
DISPLAY 0.978723 (5529 -1482);
FORCEPROP 1 LAST Q_TITLE BLOCK DIAGRAM - JTAG
J 0
(-3316 -1474);
DISPLAY 1.957447 (-3316 -1474);
PAINT GREEN (-3316 -1474);
FORCEPROP 1 LAST Q_DEPT 
J 1
(2212 -1451);
DISPLAY 1.957447 (2212 -1451);
PAINT GREEN (2212 -1451);
FORCEPROP 1 LAST COMMENT_BODY TRUE
J 0
(5987 -1513);
DISPLAY 0.978723 (5987 -1513);
PAINT GREEN (5987 -1513);
DISPLAY INVISIBLE (5987 -1513);
FORCEPROP 2 LAST PAGE_BORDER TRUE
J 0
(-1915 3750);
DISPLAY 0.638298 (-1915 3750);
PAINT PINK (-1915 3750);
DISPLAY INVISIBLE (-1915 3750);
FORCEPROP 1 LAST CDS_LMAN_SYM_OUTLINE -9475,6775,100,-125
J 0
(5975 -1500);
DISPLAY 0.468085 (5975 -1500);
PAINT GREEN (5975 -1500);
DISPLAY INVISIBLE (5975 -1500);
FORCEPROP 2 LAST CDS_LIB pure_quanta
J 0
(5975 -1500);
PAINT MONO (5975 -1500);
DISPLAY INVISIBLE (5975 -1500);
FORCEPROP 2 LAST CDS_XR_PAGE_TITLE CR-11 : @S9S_MB_2U_LIB.S9S_MB_2U(SCH_1):PAGE11
J 0
(-1915 3750);
DISPLAY 0.638298 (-1915 3750);
PAINT PINK (-1915 3750);
DISPLAY INVISIBLE (-1915 3750);
FORCEPROP 2 LAST CUSTOM_TXT_CDS <XR_PAGE_TITLE>
J 0
(-1915 3750);
DISPLAY 0.638298 (-1915 3750);
PAINT PINK (-1915 3750);
DISPLAY INVISIBLE (-1915 3750);
FORCEPROP 0 LAST CDS_CON_LAST_MODIFIED Thu Aug 24 16:12:01 2023
J 0
(4090 -1485);
PAINT MONO (4090 -1485);
DISPLAY INVISIBLE (4090 -1485);
FORCENOTE
$CDS_IMAGE|F0T_diagram_MB_20211130_rev1-JTAG (1).jpg|8759|4875
(1300 2000) 0;
DISPLAY LEFT (1300 2000);
QUIT
